FILE_TYPE = MULTI_PHYS_TABLE;

PART 'MAX15090BEWIT'

{========================================================================================}
:VALUE            | PART_TYPE | MATERIAL | PART_NUMBER      = STANDARD | LIFECYCLE | PART_NUMBER   | JEDEC_TYPE                         | DESCRIPTION                                              | MANUFTR | MANUF_PN         | RD_CMPLS_LVL | CMPLS_LVL | FROM_PJ      | CLASS | DIP_SMD | DATA                     | EE_CHECK_LIST | FP_ECN               | PSL | CREATOR | STATUS | MSD | ESD_CDM | ESD_HBM | ESD_MM | PIN_LENGTH_SHORT_PIN | PIN_LENGTH_LONG_PIN | CREATEDAY  ;
{========================================================================================}
 'MAX15090BEWI+T' | 'SMLF'    | 'IC'     | 'AL015080B00'(!) = ''       | ''        | 'AL015080B00' |'BGA28_0-5_3-525X2-065'| 'IC OTHER(28P)MAX15090BEWI+T(WLP)'                       | 'MAM'   | 'MAX15090BEWI+T' | 'EP(V1)'     | ''        | 'UH3M-KEVIN' | 'IC'  | ''      | 'MAM_MAX15090BEWI+T.pdf' | ''            | ''                   | ''  | ''      | ''     | ''  | ''      | ''      | ''     | ''                   | ''                  | '20160324'
 'MAX15090BEWI+T' | 'SMLF'    | 'EMPTY'  | 'AL015080B00'(!) = ''       | ''        | 'AL015080B00' |'BGA28_0-5_3-525X2-065'| 'IC OTHER(28P)MAX15090BEWI+T(WLP)'                       | 'MAM'   | 'MAX15090BEWI+T' | 'EP(V1)'     | ''        | 'UH3M-KEVIN' | 'IC'  | ''      | 'MAM_MAX15090BEWI+T.pdf' | ''            | ''                   | ''  | ''      | ''     | ''  | ''      | ''      | ''     | ''                   | ''                  | '20160324'
 'MAX15090BEWI+T' | 'SMLF'    | 'IC'     | 'SP_AL015080B00'(!) = ''       | ''        | 'AL015080B00' |'BGA28_0-5_3-525X2-065_SMDC9_SM13'| 'IC OTHER(28P)MAX15090BEWI+T(WLP) (PAD:9 SOLDERMASK:13)' | 'MAM'   | 'MAX15090BEWI+T' | 'EP(V1)'     | ''        | 'S8Z-IAN'    | 'IC'  | ''      | 'MAM_MAX15090BEWI+T.pdf' | ''            | 'MAX15090BEWI+T.msg' | ''  | ''      | ''     | ''  | ''      | ''      | ''     | ''                   | ''                  | '20201222'
 'MAX15090BEWI+T' | 'SMLF'    | 'EMPTY'  | 'SP_AL015080B00'(!) = ''       | ''        | 'AL015080B00' |'BGA28_0-5_3-525X2-065_SMDC9_SM13'| 'IC OTHER(28P)MAX15090BEWI+T(WLP) (PAD:9 SOLDERMASK:13)' | 'MAM'   | 'MAX15090BEWI+T' | 'EP(V1)'     | ''        | 'S8Z-IAN'    | 'IC'  | ''      | 'MAM_MAX15090BEWI+T.pdf' | ''            | 'MAX15090BEWI+T.msg' | ''  | ''      | ''     | ''  | ''      | ''      | ''     | ''                   | ''                  | '20201222'

END_PART

END.

